# T6G (Grand Teton) — schematic netlist excerpt (pin names and nets, part order shuffled) for the footprints in the layout excerpt that follows; sources: Cadence DE-HDL packaged netlist, KiCad conversion of 04192023_DAF0TMB3IC0_F0TG_MB_C_brd_V02_OCP.brd

PC2203  Q_CAP  100PF 50V 5% X7R  pkg 0402  page 147 : A = P3V3_E1S_GATE_0_PU293 ; B = GND

U23  74LVC1G08W57  74LVC1G08W5-7 IC  pkg SOT25-5_0-95_3X1-6  page 136
  A  = P12V_OCP_SFF_EN_R3
  B  = HP_LVC3_OCP_SFF_PRSNT2
  GND  = GND
  Y  = P12V_OCP_SFF_BUF_EN
  VCC  = P3V3_AUX

(kicad_pcb
	(version 20260206)
	(generator "pcbnew")
	(generator_version "10.0")
	(general
		(thickness 1.6)
		(legacy_teardrops no)
	)
	(paper "A4")
	(title_block
		(title "04192023_DAF0TMB3IC0_F0TG_MB_C_brd_V02_OCP.brd")
		(comment 1 "Grand Teton / footprints 1658-1659 of 8354")
	)
	(layers
		(0 "F.Cu" signal "TOP")
		(4 "In1.Cu" signal "GND")
		(6 "In2.Cu" signal "IN1")
		(8 "In3.Cu" signal "GND1")
		(10 "In4.Cu" signal "IN2")
		(12 "In5.Cu" signal "GND2")
		(14 "In6.Cu" signal "IN3")
		(16 "In7.Cu" signal "GND3")
		(18 "In8.Cu" signal "VCC")
		(20 "In9.Cu" signal "VCC1")
		(22 "In10.Cu" signal "GND4")
		(24 "In11.Cu" signal "IN4")
		(26 "In12.Cu" signal "GND5")
		(28 "In13.Cu" signal "IN5")
		(30 "In14.Cu" signal "GND6")
		(32 "In15.Cu" signal "IN6")
		(34 "In16.Cu" signal "GND7")
		(2 "B.Cu" signal "BOTTOM")
		(9 "F.Adhes" user "F.Adhesive")
		(11 "B.Adhes" user "B.Adhesive")
		(13 "F.Paste" user "Package Geometry/Pastemask Top")
		(15 "B.Paste" user "Package Geometry/Pastemask Bottom")
		(5 "F.SilkS" user "Ref Des/Silkscreen Top")
		(7 "B.SilkS" user "Ref Des/Silkscreen Bottom")
		(1 "F.Mask" user "Board Geometry/Soldermask Top")
		(3 "B.Mask" user "Board Geometry/Soldermask Bottom")
		(17 "Dwgs.User" user "User.Drawings")
		(19 "Cmts.User" user "User.Comments")
		(21 "Eco1.User" user "User.Eco1")
		(23 "Eco2.User" user "User.Eco2")
		(25 "Edge.Cuts" user "Board Geometry/Outline")
		(27 "Margin" user)
		(31 "F.CrtYd" user "Package Geometry/Place Bound Top")
		(29 "B.CrtYd" user "Package Geometry/Place Bound Bottom")
		(35 "F.Fab" user "Ref Des/Assembly Top")
		(33 "B.Fab" user "Ref Des/Assembly Bottom")
	)
	(footprint ""
		(layer "F.Cu")
		(at 153.543 -107.061 180)
		(property "Reference" "U23"
			(at -1.447292 2.35839 0)
			(unlocked yes)
			(layer "F.SilkS")
			(effects
				(font
					(size 0.7874 0.5842)
					(thickness 0.1524)
				)
				(justify left)
			)
		)
		(property "Value" ""
			(at 0 0 180)
			(layer "F.Fab")
			(effects
				(font
					(size 1.27 1.27)
				)
			)
		)
		(duplicate_pad_numbers_are_jumpers no)
		(fp_line
			(start 1.733296 1.549908)
			(end 1.733296 -1.549908)
			(stroke
				(width 0.1524)
				(type default)
			)
			(layer "F.SilkS")
		)
		(fp_line
			(start 1.733296 -1.549908)
			(end 0.660908 -1.549908)
			(stroke
				(width 0.1524)
				(type default)
			)
			(layer "F.SilkS")
		)
		(fp_line
			(start 0.660908 -1.549908)
			(end 0 -0.889)
			(stroke
				(width 0.1524)
				(type default)
			)
			(layer "F.SilkS")
		)
		(fp_line
			(start 0 -0.889)
			(end -0.660908 -1.549908)
			(stroke
				(width 0.1524)
				(type default)
			)
			(layer "F.SilkS")
		)
		(fp_line
			(start -0.660908 -1.549908)
			(end -1.733296 -1.549908)
			(stroke
				(width 0.1524)
				(type default)
			)
			(layer "F.SilkS")
		)
		(fp_line
			(start -1.733296 1.549908)
			(end 1.733296 1.549908)
			(stroke
				(width 0.1524)
				(type default)
			)
			(layer "F.SilkS")
		)
		(fp_line
			(start -1.733296 -1.549908)
			(end -1.733296 1.549908)
			(stroke
				(width 0.1524)
				(type default)
			)
			(layer "F.SilkS")
		)
		(fp_poly
			(pts
				(xy -2.17297 -2.058162) (xy -2.488692 -1.660144) (xy -1.932686 -1.543558)
			)
			(stroke
				(width 0)
				(type default)
			)
			(fill yes)
			(layer "F.SilkS")
		)
		(fp_line
			(start 0.849884 1.549908)
			(end 0.849884 -1.549908)
			(stroke
				(width 0.1)
				(type default)
			)
			(layer "F.Fab")
		)
		(fp_line
			(start 0.849884 -1.549908)
			(end -0.849884 -1.549908)
			(stroke
				(width 0.1)
				(type default)
			)
			(layer "F.Fab")
		)
		(fp_line
			(start -0.849884 1.549908)
			(end 0.849884 1.549908)
			(stroke
				(width 0.1)
				(type default)
			)
			(layer "F.Fab")
		)
		(fp_line
			(start -0.849884 -1.549908)
			(end -0.849884 1.549908)
			(stroke
				(width 0.1)
				(type default)
			)
			(layer "F.Fab")
		)
		(fp_poly
			(pts
				(xy -2.4384 -1.20396) (xy -2.4384 -0.69596) (xy -1.9304 -0.94996)
			)
			(stroke
				(width 0)
				(type default)
			)
			(fill yes)
			(layer "F.Fab")
		)
		(pad "1" smd rect
			(at -1.199896 -0.94996 90)
			(size 0.5588 0.8128)
			(layers "F.Cu" "F.Mask" "F.Paste")
			(net "P12V_OCP_SFF_EN_R3")
		)
		(pad "2" smd rect
			(at -1.199896 0 90)
			(size 0.5588 0.8128)
			(layers "F.Cu" "F.Mask" "F.Paste")
			(net "HP_LVC3_OCP_SFF_PRSNT2")
		)
		(pad "3" smd rect
			(at -1.199896 0.94996 90)
			(size 0.5588 0.8128)
			(layers "F.Cu" "F.Mask" "F.Paste")
			(net "GND")
		)
		(pad "4" smd rect
			(at 1.199896 0.94996 90)
			(size 0.5588 0.8128)
			(layers "F.Cu" "F.Mask" "F.Paste")
			(net "P12V_OCP_SFF_BUF_EN")
		)
		(pad "5" smd rect
			(at 1.199896 -0.94996 90)
			(size 0.5588 0.8128)
			(layers "F.Cu" "F.Mask" "F.Paste")
			(net "P3V3_AUX")
		)
	)
	(footprint ""
		(layer "F.Cu")
		(at 200.600564 -68.026788)
		(property "Reference" "PC2203"
			(at 0 0 0)
			(layer "F.SilkS")
			(hide yes)
			(effects
				(font
					(size 1.27 1.27)
				)
			)
		)
		(property "Value" ""
			(at 0 0 0)
			(layer "F.Fab")
			(effects
				(font
					(size 1.27 1.27)
				)
			)
		)
		(duplicate_pad_numbers_are_jumpers no)
		(fp_line
			(start -0.7874 -0.4064)
			(end 0.7874 -0.4064)
			(stroke
				(width 0.1524)
				(type default)
			)
			(layer "F.SilkS")
		)
		(fp_line
			(start -0.7874 0.4064)
			(end -0.7874 -0.4064)
			(stroke
				(width 0.1524)
				(type default)
			)
			(layer "F.SilkS")
		)
		(fp_line
			(start 0.7874 -0.4064)
			(end 0.7874 0.4064)
			(stroke
				(width 0.1524)
				(type default)
			)
			(layer "F.SilkS")
		)
		(fp_line
			(start 0.7874 0.4064)
			(end -0.7874 0.4064)
			(stroke
				(width 0.1524)
				(type default)
			)
			(layer "F.SilkS")
		)
		(fp_line
			(start -0.67945 -0.305054)
			(end -0.12065 -0.305054)
			(stroke
				(width 0.1)
				(type default)
			)
			(layer "F.Fab")
		)
		(fp_line
			(start -0.67945 0.3048)
			(end -0.67945 -0.305054)
			(stroke
				(width 0.1)
				(type default)
			)
			(layer "F.Fab")
		)
		(fp_line
			(start -0.12065 -0.305054)
			(end -0.12065 -0.2794)
			(stroke
				(width 0.1)
				(type default)
			)
			(layer "F.Fab")
		)
		(fp_line
			(start -0.12065 -0.2794)
			(end 0.12065 -0.2794)
			(stroke
				(width 0.1)
				(type default)
			)
			(layer "F.Fab")
		)
		(fp_line
			(start -0.12065 0.2794)
			(end -0.12065 0.3048)
			(stroke
				(width 0.1)
				(type default)
			)
			(layer "F.Fab")
		)
		(fp_line
			(start -0.12065 0.3048)
			(end -0.67945 0.3048)
			(stroke
				(width 0.1)
				(type default)
			)
			(layer "F.Fab")
		)
		(fp_line
			(start 0.120396 0.2794)
			(end -0.12065 0.2794)
			(stroke
				(width 0.1)
				(type default)
			)
			(layer "F.Fab")
		)
		(fp_line
			(start 0.120396 0.3048)
			(end 0.120396 0.2794)
			(stroke
				(width 0.1)
				(type default)
			)
			(layer "F.Fab")
		)
		(fp_line
			(start 0.12065 -0.3048)
			(end 0.67945 -0.3048)
			(stroke
				(width 0.1)
				(type default)
			)
			(layer "F.Fab")
		)
		(fp_line
			(start 0.12065 -0.2794)
			(end 0.12065 -0.3048)
			(stroke
				(width 0.1)
				(type default)
			)
			(layer "F.Fab")
		)
		(fp_line
			(start 0.67945 -0.3048)
			(end 0.67945 0.3048)
			(stroke
				(width 0.1)
				(type default)
			)
			(layer "F.Fab")
		)
		(fp_line
			(start 0.67945 0.3048)
			(end 0.120396 0.3048)
			(stroke
				(width 0.1)
				(type default)
			)
			(layer "F.Fab")
		)
		(pad "1" smd circle
			(at -0.40005 0)
			(size 0 0)
			(layers "F.Cu" "F.Mask" "F.Paste")
			(net "P3V3_E1S_GATE_0_PU293")
		)
		(pad "2" smd circle
			(at 0.40005 0)
			(size 0 0)
			(layers "F.Cu" "F.Mask" "F.Paste")
			(net "GND")
		)
	)
)
